# BASEBOARD_FAB2 (Tioga Pass) — schematic netlist excerpt (pin names and nets, part order shuffled) for the footprints in the layout excerpt that follows; sources: Cadence DE-HDL packaged netlist, KiCad conversion of Wiwynn_Tioga_Pass_MB.brd

R8E14  RES  4.75K 1% CHIP  pkg 0402  page 136 : A = P3V3_STBY ; B = RST_PLTRST_TOP_SWAP
R7E5  RES  10.0K 1% CHIP  pkg 0402  page 192 : A = P3V3_STBY ; B = PU_THERMTRIP_FORCE_N
C7C9  CAP_A  22.0UF 4V 20% X6S  pkg 0603V  page 132 : A = PVNN_PCH_STBY ; B = GND

(kicad_pcb
	(version 20260206)
	(generator "pcbnew")
	(generator_version "10.0")
	(general
		(thickness 1.6)
		(legacy_teardrops no)
	)
	(paper "A4")
	(title_block
		(title "Wiwynn_Tioga_Pass_MB.brd")
		(comment 1 "Tioga Pass / footprints 1981-1983 of 4770")
	)
	(layers
		(0 "F.Cu" signal "TOP")
		(4 "In1.Cu" signal "L2GND")
		(6 "In2.Cu" signal "L3")
		(8 "In3.Cu" signal "L4GND")
		(10 "In4.Cu" signal "L5")
		(12 "In5.Cu" signal "L6GND")
		(14 "In6.Cu" signal "L7VCC")
		(16 "In7.Cu" signal "L8VCC")
		(18 "In8.Cu" signal "L9GND")
		(20 "In9.Cu" signal "L10")
		(22 "In10.Cu" signal "L11GND")
		(24 "In11.Cu" signal "L12")
		(26 "In12.Cu" signal "L13GND")
		(2 "B.Cu" signal "BOTTOM")
		(9 "F.Adhes" user "F.Adhesive")
		(11 "B.Adhes" user "B.Adhesive")
		(13 "F.Paste" user "Package Geometry/Pastemask Top")
		(15 "B.Paste" user "Package Geometry/Pastemask Bottom")
		(5 "F.SilkS" user "Ref Des/Silkscreen Top")
		(7 "B.SilkS" user "Ref Des/Silkscreen Bottom")
		(1 "F.Mask" user "Board Geometry/Soldermask Top")
		(3 "B.Mask" user "Board Geometry/Soldermask Bottom")
		(17 "Dwgs.User" user "User.Drawings")
		(19 "Cmts.User" user "User.Comments")
		(21 "Eco1.User" user "User.Eco1")
		(23 "Eco2.User" user "User.Eco2")
		(25 "Edge.Cuts" user "Board Geometry/Outline")
		(27 "Margin" user)
		(31 "F.CrtYd" user "Package Geometry/Place Bound Top")
		(29 "B.CrtYd" user "Package Geometry/Place Bound Bottom")
		(35 "F.Fab" user "Ref Des/Assembly Top")
		(33 "B.Fab" user "Ref Des/Assembly Bottom")
	)
	(footprint ""
		(layer "F.Cu")
		(at 367.116106 -64.81064 90)
		(property "Reference" "R7E5"
			(at 0 0 90)
			(layer "F.SilkS")
			(hide yes)
			(effects
				(font
					(size 1.27 1.27)
				)
			)
		)
		(property "Value" ""
			(at 0 0 90)
			(layer "F.Fab")
			(effects
				(font
					(size 1.27 1.27)
				)
			)
		)
		(duplicate_pad_numbers_are_jumpers no)
		(fp_poly
			(pts
				(xy -0.2794 -0.1016) (xy 0.2794 -0.1016) (xy 0.2794 0.9906) (xy -0.2794 0.9906)
			)
			(stroke
				(width 0)
				(type default)
			)
			(fill no)
			(layer "F.CrtYd")
		)
		(fp_line
			(start 0.2794 -0.1016)
			(end -0.2794 -0.1016)
			(stroke
				(width 0.1)
				(type default)
			)
			(layer "F.Fab")
		)
		(fp_line
			(start -0.2794 -0.1016)
			(end -0.2794 0.9906)
			(stroke
				(width 0.1)
				(type default)
			)
			(layer "F.Fab")
		)
		(fp_line
			(start 0.2794 0.9906)
			(end 0.2794 -0.1016)
			(stroke
				(width 0.1)
				(type default)
			)
			(layer "F.Fab")
		)
		(fp_line
			(start -0.2794 0.9906)
			(end 0.2794 0.9906)
			(stroke
				(width 0.1)
				(type default)
			)
			(layer "F.Fab")
		)
		(pad "1" smd rect
			(at 0 0 90)
			(size 0.508 0.508)
			(layers "F.Cu" "F.Mask" "F.Paste")
			(net "P3V3_STBY")
		)
		(pad "2" smd rect
			(at 0 0.889 90)
			(size 0.508 0.508)
			(layers "F.Cu" "F.Mask" "F.Paste")
			(net "PU_THERMTRIP_FORCE_N")
		)
		(zone
			(layer "F.Cu")
			(hatch none 0.5)
			(connect_pads
				(clearance 0)
			)
			(min_thickness 0.25)
			(keepout
				(tracks allowed)
				(vias not_allowed)
				(pads allowed)
				(copperpour not_allowed)
				(footprints allowed)
			)
			(placement
				(enabled no)
				(sheetname "")
			)
			(fill
				(thermal_gap 0.5)
				(thermal_bridge_width 0.5)
				(island_removal_mode 0)
			)
			(polygon
				(pts
					(xy 367.370106 -64.55664) (xy 367.370106 -65.06464) (xy 367.751106 -65.06464) (xy 367.751106 -64.55664)
				)
			)
		)
		(zone
			(layer "F.Cu")
			(hatch none 0.5)
			(connect_pads
				(clearance 0)
			)
			(min_thickness 0.25)
			(keepout
				(tracks not_allowed)
				(vias allowed)
				(pads allowed)
				(copperpour not_allowed)
				(footprints allowed)
			)
			(placement
				(enabled no)
				(sheetname "")
			)
			(fill
				(thermal_gap 0.5)
				(thermal_bridge_width 0.5)
				(island_removal_mode 0)
			)
			(polygon
				(pts
					(xy 367.751106 -64.55664) (xy 367.751106 -65.06464) (xy 367.370106 -65.06464) (xy 367.370106 -64.55664)
				)
			)
		)
	)
	(footprint ""
		(layer "F.Cu")
		(at 417.9316 -57.1119 180)
		(property "Reference" "R8E14"
			(at 0 0 180)
			(layer "F.SilkS")
			(hide yes)
			(effects
				(font
					(size 1.27 1.27)
				)
			)
		)
		(property "Value" ""
			(at 0 0 180)
			(layer "F.Fab")
			(effects
				(font
					(size 1.27 1.27)
				)
			)
		)
		(duplicate_pad_numbers_are_jumpers no)
		(fp_poly
			(pts
				(xy -0.2794 -0.1016) (xy 0.2794 -0.1016) (xy 0.2794 0.9906) (xy -0.2794 0.9906)
			)
			(stroke
				(width 0)
				(type default)
			)
			(fill no)
			(layer "F.CrtYd")
		)
		(fp_line
			(start 0.2794 0.9906)
			(end 0.2794 -0.1016)
			(stroke
				(width 0.1)
				(type default)
			)
			(layer "F.Fab")
		)
		(fp_line
			(start 0.2794 -0.1016)
			(end -0.2794 -0.1016)
			(stroke
				(width 0.1)
				(type default)
			)
			(layer "F.Fab")
		)
		(fp_line
			(start -0.2794 0.9906)
			(end 0.2794 0.9906)
			(stroke
				(width 0.1)
				(type default)
			)
			(layer "F.Fab")
		)
		(fp_line
			(start -0.2794 -0.1016)
			(end -0.2794 0.9906)
			(stroke
				(width 0.1)
				(type default)
			)
			(layer "F.Fab")
		)
		(pad "1" smd rect
			(at 0 0 180)
			(size 0.508 0.508)
			(layers "F.Cu" "F.Mask" "F.Paste")
			(net "P3V3_STBY")
		)
		(pad "2" smd rect
			(at 0 0.889 180)
			(size 0.508 0.508)
			(layers "F.Cu" "F.Mask" "F.Paste")
			(net "RST_PLTRST_TOP_SWAP")
		)
		(zone
			(layer "F.Cu")
			(hatch none 0.5)
			(connect_pads
				(clearance 0)
			)
			(min_thickness 0.25)
			(keepout
				(tracks not_allowed)
				(vias allowed)
				(pads allowed)
				(copperpour not_allowed)
				(footprints allowed)
			)
			(placement
				(enabled no)
				(sheetname "")
			)
			(fill
				(thermal_gap 0.5)
				(thermal_bridge_width 0.5)
				(island_removal_mode 0)
			)
			(polygon
				(pts
					(xy 418.1856 -57.7469) (xy 417.6776 -57.7469) (xy 417.6776 -57.3659) (xy 418.1856 -57.3659)
				)
			)
		)
		(zone
			(layer "F.Cu")
			(hatch none 0.5)
			(connect_pads
				(clearance 0)
			)
			(min_thickness 0.25)
			(keepout
				(tracks allowed)
				(vias not_allowed)
				(pads allowed)
				(copperpour not_allowed)
				(footprints allowed)
			)
			(placement
				(enabled no)
				(sheetname "")
			)
			(fill
				(thermal_gap 0.5)
				(thermal_bridge_width 0.5)
				(island_removal_mode 0)
			)
			(polygon
				(pts
					(xy 418.1856 -57.3659) (xy 417.6776 -57.3659) (xy 417.6776 -57.7469) (xy 418.1856 -57.7469)
				)
			)
		)
	)
	(footprint ""
		(layer "F.Cu")
		(at 368.184938 -102.30739 -90)
		(property "Reference" "C7C9"
			(at 0 0 270)
			(layer "F.SilkS")
			(hide yes)
			(effects
				(font
					(size 1.27 1.27)
				)
			)
		)
		(property "Value" ""
			(at 0 0 270)
			(layer "F.Fab")
			(effects
				(font
					(size 1.27 1.27)
				)
			)
		)
		(duplicate_pad_numbers_are_jumpers no)
		(fp_poly
			(pts
				(xy -0.4953 -0.2032) (xy 0.4953 -0.2032) (xy 0.4953 1.6002) (xy -0.4953 1.6002)
			)
			(stroke
				(width 0)
				(type default)
			)
			(fill no)
			(layer "F.CrtYd")
		)
		(fp_line
			(start -0.4953 1.6002)
			(end -0.4953 -0.2032)
			(stroke
				(width 0.1)
				(type default)
			)
			(layer "F.Fab")
		)
		(fp_line
			(start 0.4953 1.6002)
			(end -0.4953 1.6002)
			(stroke
				(width 0.1)
				(type default)
			)
			(layer "F.Fab")
		)
		(fp_line
			(start -0.4953 -0.2032)
			(end 0.4953 -0.2032)
			(stroke
				(width 0.1)
				(type default)
			)
			(layer "F.Fab")
		)
		(fp_line
			(start 0.4953 -0.2032)
			(end 0.4953 1.6002)
			(stroke
				(width 0.1)
				(type default)
			)
			(layer "F.Fab")
		)
		(pad "1" smd rect
			(at 0 0 270)
			(size 0.762 0.889)
			(layers "F.Cu" "F.Mask" "F.Paste")
			(net "PVNN_PCH_STBY")
		)
		(pad "2" smd rect
			(at 0 1.397 270)
			(size 0.762 0.889)
			(layers "F.Cu" "F.Mask" "F.Paste")
			(net "GND")
		)
		(zone
			(layer "F.Cu")
			(hatch none 0.5)
			(connect_pads
				(clearance 0)
			)
			(min_thickness 0.25)
			(keepout
				(tracks not_allowed)
				(vias allowed)
				(pads allowed)
				(copperpour not_allowed)
				(footprints allowed)
			)
			(placement
				(enabled no)
				(sheetname "")
			)
			(fill
				(thermal_gap 0.5)
				(thermal_bridge_width 0.5)
				(island_removal_mode 0)
			)
			(polygon
				(pts
					(xy 367.740438 -102.68839) (xy 367.740438 -101.92639) (xy 367.232438 -101.92639) (xy 367.232438 -102.68839)
				)
			)
		)
	)
)
